(kicad_pcb
	(version 20260206)
	(generator "pcbnew")
	(generator_version "10.0")
	(general
		(thickness 1.6)
		(legacy_teardrops no)
	)
	(paper "A4")
	(title_block
		(title "pdpb — Lightning_PDPB_BRD.brd")
		(comment 1 "Lightning (Wiwynn / Facebook NVMe JBOF) / footprint 523 of 1140 (J18), pads 115-202 of 202")
	)
	(layers
		(0 "F.Cu" signal "TOP")
		(4 "In1.Cu" signal "L2GND")
		(6 "In2.Cu" signal "L3")
		(8 "In3.Cu" signal "L4VCC")
		(10 "In4.Cu" signal "L5VCC")
		(12 "In5.Cu" signal "L6")
		(14 "In6.Cu" signal "L7GND")
		(2 "B.Cu" signal "BOTTOM")
		(9 "F.Adhes" user "F.Adhesive")
		(11 "B.Adhes" user "B.Adhesive")
		(13 "F.Paste" user "Package Geometry/Pastemask Top")
		(15 "B.Paste" user "Package Geometry/Pastemask Bottom")
		(5 "F.SilkS" user "Ref Des/Silkscreen Top")
		(7 "B.SilkS" user "Ref Des/Silkscreen Bottom")
		(1 "F.Mask" user "Board Geometry/Soldermask Top")
		(3 "B.Mask" user "Board Geometry/Soldermask Bottom")
		(17 "Dwgs.User" user "User.Drawings")
		(19 "Cmts.User" user "User.Comments")
		(21 "Eco1.User" user "User.Eco1")
		(23 "Eco2.User" user "User.Eco2")
		(25 "Edge.Cuts" user "Board Geometry/Outline")
		(27 "Margin" user)
		(31 "F.CrtYd" user "Package Geometry/Place Bound Top")
		(29 "B.CrtYd" user "Package Geometry/Place Bound Bottom")
		(35 "F.Fab" user "Ref Des/Assembly Top")
		(33 "B.Fab" user "Ref Des/Assembly Bottom")
	)
	(footprint ""
		(layer "F.Cu")
		(at 2.999994 -319.14211 90)
		(property "Reference" "J18"
			(at 0 0 90)
			(layer "F.SilkS")
			(hide yes)
			(effects
				(font
					(size 1.27 1.27)
				)
			)
		)
		(property "Value" "PCISLT200-5-GP-U"
			(at -48.7045 -6.7818 90)
			(unlocked yes)
			(layer "F.Fab")
			(hide yes)
			(effects
				(font
					(size 1.016 1.016)
					(thickness 0.1524)
				)
			)
		)
		(property "Device Type" "G639F200221431HR-U"
			(at -48.7045 -8.3058 90)
			(unlocked yes)
			(layer "F.Fab")
			(hide yes)
			(effects
				(font
					(size 1.016 1.016)
					(thickness 0.1524)
				)
			)
		)
		(duplicate_pad_numbers_are_jumpers no)
		(pad "B13" smd rect
			(at -31.599886 -1.131062 90)
			(size 0.508 2.4892)
			(drill
				(offset 0 0.381)
			)
			(layers "F.Cu" "F.Mask" "F.Paste")
			(net "ATTN_LED_DR12_N")
		)
		(pad "B14" smd rect
			(at -30.80004 -1.131062 90)
			(size 0.508 2.4892)
			(drill
				(offset 0 0.381)
			)
			(layers "F.Cu" "F.Mask" "F.Paste")
			(net "SSD12_CLK0_OE_R_N")
		)
		(pad "B15" smd rect
			(at -29.99994 -1.131062 90)
			(size 0.508 2.4892)
			(drill
				(offset 0 0.381)
			)
			(layers "F.Cu" "F.Mask" "F.Paste")
			(net "GND")
		)
		(pad "B16" smd rect
			(at -29.200094 -1.131062 90)
			(size 0.508 2.4892)
			(drill
				(offset 0 0.381)
			)
			(layers "F.Cu" "F.Mask" "F.Paste")
			(net "PE_RX1_DR3_N")
		)
		(pad "B17" smd rect
			(at -28.399994 -1.131062 90)
			(size 0.508 2.4892)
			(drill
				(offset 0 0.381)
			)
			(layers "F.Cu" "F.Mask" "F.Paste")
			(net "PE_RX1_DR3_P")
		)
		(pad "B18" smd rect
			(at -27.599894 -1.131062 90)
			(size 0.508 2.4892)
			(drill
				(offset 0 0.381)
			)
			(layers "F.Cu" "F.Mask" "F.Paste")
			(net "GND")
		)
		(pad "B19" smd rect
			(at -26.800048 -1.131062 90)
			(size 0.508 2.4892)
			(drill
				(offset 0 0.381)
			)
			(layers "F.Cu" "F.Mask" "F.Paste")
			(net "GND")
		)
		(pad "B20" smd rect
			(at -25.999948 -1.131062 90)
			(size 0.508 2.4892)
			(drill
				(offset 0 0.381)
			)
			(layers "F.Cu" "F.Mask" "F.Paste")
			(net "PE_RX2_DR3_N")
		)
		(pad "B21" smd rect
			(at -25.200102 -1.131062 90)
			(size 0.508 2.4892)
			(drill
				(offset 0 0.381)
			)
			(layers "F.Cu" "F.Mask" "F.Paste")
			(net "PE_RX2_DR3_P")
		)
		(pad "B22" smd rect
			(at -24.400002 -1.131062 90)
			(size 0.508 2.4892)
			(drill
				(offset 0 0.381)
			)
			(layers "F.Cu" "F.Mask" "F.Paste")
			(net "GND")
		)
		(pad "B23" smd rect
			(at -23.599902 -1.131062 90)
			(size 0.508 2.4892)
			(drill
				(offset 0 0.381)
			)
			(layers "F.Cu" "F.Mask" "F.Paste")
			(net "GND")
		)
		(pad "B24" smd rect
			(at -22.800056 -1.131062 90)
			(size 0.508 2.4892)
			(drill
				(offset 0 0.381)
			)
			(layers "F.Cu" "F.Mask" "F.Paste")
			(net "PE_RX3_DR3_N")
		)
		(pad "B25" smd rect
			(at -21.999956 -1.131062 90)
			(size 0.508 2.4892)
			(drill
				(offset 0 0.381)
			)
			(layers "F.Cu" "F.Mask" "F.Paste")
			(net "PE_RX3_DR3_P")
		)
		(pad "B26" smd rect
			(at -21.20011 -1.131062 90)
			(size 0.508 2.4892)
			(drill
				(offset 0 0.381)
			)
			(layers "F.Cu" "F.Mask" "F.Paste")
			(net "GND")
		)
		(pad "B27" smd rect
			(at -20.40001 -1.131062 90)
			(size 0.508 2.4892)
			(drill
				(offset 0 0.381)
			)
			(layers "F.Cu" "F.Mask" "F.Paste")
			(net "GND")
		)
		(pad "B28" smd rect
			(at -19.59991 -1.131062 90)
			(size 0.508 2.4892)
			(drill
				(offset 0 0.381)
			)
			(layers "F.Cu" "F.Mask" "F.Paste")
			(net "PE_RX4_DR3_N")
		)
		(pad "B29" smd rect
			(at -18.800064 -1.131062 90)
			(size 0.508 2.4892)
			(drill
				(offset 0 0.381)
			)
			(layers "F.Cu" "F.Mask" "F.Paste")
			(net "PE_RX4_DR3_P")
		)
		(pad "B30" smd rect
			(at -17.999964 -1.131062 90)
			(size 0.508 2.4892)
			(drill
				(offset 0 0.381)
			)
			(layers "F.Cu" "F.Mask" "F.Paste")
			(net "GND")
		)
		(pad "B31" smd rect
			(at -17.200118 -1.131062 90)
			(size 0.508 2.4892)
			(drill
				(offset 0 0.381)
			)
			(layers "F.Cu" "F.Mask" "F.Paste")
			(net "GND")
		)
		(pad "B32" smd rect
			(at -16.400018 -1.131062 90)
			(size 0.508 2.4892)
			(drill
				(offset 0 0.381)
			)
			(layers "F.Cu" "F.Mask" "F.Paste")
			(net "PE_RX1_DR7_N")
		)
		(pad "B33" smd rect
			(at -15.599918 -1.131062 90)
			(size 0.508 2.4892)
			(drill
				(offset 0 0.381)
			)
			(layers "F.Cu" "F.Mask" "F.Paste")
			(net "PE_RX1_DR7_P")
		)
		(pad "B34" smd rect
			(at -14.800072 -1.131062 90)
			(size 0.508 2.4892)
			(drill
				(offset 0 0.381)
			)
			(layers "F.Cu" "F.Mask" "F.Paste")
			(net "GND")
		)
		(pad "B35" smd rect
			(at -13.999972 -1.131062 90)
			(size 0.508 2.4892)
			(drill
				(offset 0 0.381)
			)
			(layers "F.Cu" "F.Mask" "F.Paste")
			(net "GND")
		)
		(pad "B36" smd rect
			(at -13.200126 -1.131062 90)
			(size 0.508 2.4892)
			(drill
				(offset 0 0.381)
			)
			(layers "F.Cu" "F.Mask" "F.Paste")
			(net "PE_RX2_DR7_N")
		)
		(pad "B37" smd rect
			(at -12.400026 -1.131062 90)
			(size 0.508 2.4892)
			(drill
				(offset 0 0.381)
			)
			(layers "F.Cu" "F.Mask" "F.Paste")
			(net "PE_RX2_DR7_P")
		)
		(pad "B38" smd rect
			(at -11.599926 -1.131062 90)
			(size 0.508 2.4892)
			(drill
				(offset 0 0.381)
			)
			(layers "F.Cu" "F.Mask" "F.Paste")
			(net "GND")
		)
		(pad "B39" smd rect
			(at -10.80008 -1.131062 90)
			(size 0.508 2.4892)
			(drill
				(offset 0 0.381)
			)
			(layers "F.Cu" "F.Mask" "F.Paste")
			(net "GND")
		)
		(pad "B40" smd rect
			(at -9.99998 -1.131062 90)
			(size 0.508 2.4892)
			(drill
				(offset 0 0.381)
			)
			(layers "F.Cu" "F.Mask" "F.Paste")
			(net "PE_RX3_DR7_N")
		)
		(pad "B41" smd rect
			(at -9.19988 -1.131062 90)
			(size 0.508 2.4892)
			(drill
				(offset 0 0.381)
			)
			(layers "F.Cu" "F.Mask" "F.Paste")
			(net "PE_RX3_DR7_P")
		)
		(pad "B42" smd rect
			(at -8.400034 -1.131062 90)
			(size 0.508 2.4892)
			(drill
				(offset 0 0.381)
			)
			(layers "F.Cu" "F.Mask" "F.Paste")
			(net "GND")
		)
		(pad "B43" smd rect
			(at -7.599934 -1.131062 90)
			(size 0.508 2.4892)
			(drill
				(offset 0 0.381)
			)
			(layers "F.Cu" "F.Mask" "F.Paste")
			(net "SSD7_PERST_N")
		)
		(pad "B44" smd rect
			(at -6.800088 -1.131062 90)
			(size 0.508 2.4892)
			(drill
				(offset 0 0.381)
			)
			(layers "F.Cu" "F.Mask" "F.Paste")
			(net "SSD7_PWREN")
		)
		(pad "B45" smd rect
			(at -2.800096 -1.131062 90)
			(size 0.508 2.4892)
			(drill
				(offset 0 0.381)
			)
			(layers "F.Cu" "F.Mask" "F.Paste")
			(net "GND")
		)
		(pad "B46" smd rect
			(at -1.999996 -1.131062 90)
			(size 0.508 2.4892)
			(drill
				(offset 0 0.381)
			)
			(layers "F.Cu" "F.Mask" "F.Paste")
			(net "PE_RX4_DR7_N")
		)
		(pad "B47" smd rect
			(at -1.199896 -1.131062 90)
			(size 0.508 2.4892)
			(drill
				(offset 0 0.381)
			)
			(layers "F.Cu" "F.Mask" "F.Paste")
			(net "PE_RX4_DR7_P")
		)
		(pad "B48" smd rect
			(at -0.40005 -1.131062 90)
			(size 0.508 2.4892)
			(drill
				(offset 0 0.381)
			)
			(layers "F.Cu" "F.Mask" "F.Paste")
			(net "GND")
		)
		(pad "B49" smd rect
			(at 0.40005 -1.131062 90)
			(size 0.508 2.4892)
			(drill
				(offset 0 0.381)
			)
			(layers "F.Cu" "F.Mask" "F.Paste")
			(net "GND")
		)
		(pad "B50" smd rect
			(at 1.199896 -1.131062 90)
			(size 0.508 2.4892)
			(drill
				(offset 0 0.381)
			)
			(layers "F.Cu" "F.Mask" "F.Paste")
			(net "PE_RX1_DR2_N")
		)
		(pad "B51" smd rect
			(at 1.999996 -1.131062 90)
			(size 0.508 2.4892)
			(drill
				(offset 0 0.381)
			)
			(layers "F.Cu" "F.Mask" "F.Paste")
			(net "PE_RX1_DR2_P")
		)
		(pad "B52" smd rect
			(at 2.800096 -1.131062 90)
			(size 0.508 2.4892)
			(drill
				(offset 0 0.381)
			)
			(layers "F.Cu" "F.Mask" "F.Paste")
			(net "GND")
		)
		(pad "B53" smd rect
			(at 3.599942 -1.131062 90)
			(size 0.508 2.4892)
			(drill
				(offset 0 0.381)
			)
			(layers "F.Cu" "F.Mask" "F.Paste")
			(net "GND")
		)
		(pad "B54" smd rect
			(at 4.400042 -1.131062 90)
			(size 0.508 2.4892)
			(drill
				(offset 0 0.381)
			)
			(layers "F.Cu" "F.Mask" "F.Paste")
			(net "PE_RX2_DR2_N")
		)
		(pad "B55" smd rect
			(at 5.199888 -1.131062 90)
			(size 0.508 2.4892)
			(drill
				(offset 0 0.381)
			)
			(layers "F.Cu" "F.Mask" "F.Paste")
			(net "PE_RX2_DR2_P")
		)
		(pad "B56" smd rect
			(at 5.999988 -1.131062 90)
			(size 0.508 2.4892)
			(drill
				(offset 0 0.381)
			)
			(layers "F.Cu" "F.Mask" "F.Paste")
			(net "GND")
		)
		(pad "B57" smd rect
			(at 6.800088 -1.131062 90)
			(size 0.508 2.4892)
			(drill
				(offset 0 0.381)
			)
			(layers "F.Cu" "F.Mask" "F.Paste")
			(net "GND")
		)
		(pad "B58" smd rect
			(at 7.599934 -1.131062 90)
			(size 0.508 2.4892)
			(drill
				(offset 0 0.381)
			)
			(layers "F.Cu" "F.Mask" "F.Paste")
			(net "PE_RX3_DR2_N")
		)
		(pad "B59" smd rect
			(at 8.400034 -1.131062 90)
			(size 0.508 2.4892)
			(drill
				(offset 0 0.381)
			)
			(layers "F.Cu" "F.Mask" "F.Paste")
			(net "PE_RX3_DR2_P")
		)
		(pad "B60" smd rect
			(at 9.19988 -1.131062 90)
			(size 0.508 2.4892)
			(drill
				(offset 0 0.381)
			)
			(layers "F.Cu" "F.Mask" "F.Paste")
			(net "GND")
		)
		(pad "B61" smd rect
			(at 9.99998 -1.131062 90)
			(size 0.508 2.4892)
			(drill
				(offset 0 0.381)
			)
			(layers "F.Cu" "F.Mask" "F.Paste")
			(net "GND")
		)
		(pad "B62" smd rect
			(at 10.80008 -1.131062 90)
			(size 0.508 2.4892)
			(drill
				(offset 0 0.381)
			)
			(layers "F.Cu" "F.Mask" "F.Paste")
			(net "PE_RX4_DR2_N")
		)
		(pad "B63" smd rect
			(at 11.599926 -1.131062 90)
			(size 0.508 2.4892)
			(drill
				(offset 0 0.381)
			)
			(layers "F.Cu" "F.Mask" "F.Paste")
			(net "PE_RX4_DR2_P")
		)
		(pad "B64" smd rect
			(at 12.400026 -1.131062 90)
			(size 0.508 2.4892)
			(drill
				(offset 0 0.381)
			)
			(layers "F.Cu" "F.Mask" "F.Paste")
			(net "GND")
		)
		(pad "B65" smd rect
			(at 13.200126 -1.131062 90)
			(size 0.508 2.4892)
			(drill
				(offset 0 0.381)
			)
			(layers "F.Cu" "F.Mask" "F.Paste")
			(net "SSD11_PWREN")
		)
		(pad "B66" smd rect
			(at 13.999972 -1.131062 90)
			(size 0.508 2.4892)
			(drill
				(offset 0 0.381)
			)
			(layers "F.Cu" "F.Mask" "F.Paste")
			(net "ATTN_LED_DR11_N")
		)
		(pad "B67" smd rect
			(at 14.800072 -1.131062 90)
			(size 0.508 2.4892)
			(drill
				(offset 0 0.381)
			)
			(layers "F.Cu" "F.Mask" "F.Paste")
			(net "SSD11_CLK0_OE_R_N")
		)
		(pad "B68" smd rect
			(at 15.599918 -1.131062 90)
			(size 0.508 2.4892)
			(drill
				(offset 0 0.381)
			)
			(layers "F.Cu" "F.Mask" "F.Paste")
			(net "GND")
		)
		(pad "B69" smd rect
			(at 16.400018 -1.131062 90)
			(size 0.508 2.4892)
			(drill
				(offset 0 0.381)
			)
			(layers "F.Cu" "F.Mask" "F.Paste")
			(net "PE_RX1_DR11_N")
		)
		(pad "B70" smd rect
			(at 17.200118 -1.131062 90)
			(size 0.508 2.4892)
			(drill
				(offset 0 0.381)
			)
			(layers "F.Cu" "F.Mask" "F.Paste")
			(net "PE_RX1_DR11_P")
		)
		(pad "B71" smd rect
			(at 17.999964 -1.131062 90)
			(size 0.508 2.4892)
			(drill
				(offset 0 0.381)
			)
			(layers "F.Cu" "F.Mask" "F.Paste")
			(net "GND")
		)
		(pad "B72" smd rect
			(at 18.800064 -1.131062 90)
			(size 0.508 2.4892)
			(drill
				(offset 0 0.381)
			)
			(layers "F.Cu" "F.Mask" "F.Paste")
			(net "GND")
		)
		(pad "B73" smd rect
			(at 19.59991 -1.131062 90)
			(size 0.508 2.4892)
			(drill
				(offset 0 0.381)
			)
			(layers "F.Cu" "F.Mask" "F.Paste")
			(net "PE_RX2_DR11_N")
		)
		(pad "B74" smd rect
			(at 20.40001 -1.131062 90)
			(size 0.508 2.4892)
			(drill
				(offset 0 0.381)
			)
			(layers "F.Cu" "F.Mask" "F.Paste")
			(net "PE_RX2_DR11_P")
		)
		(pad "B75" smd rect
			(at 21.20011 -1.131062 90)
			(size 0.508 2.4892)
			(drill
				(offset 0 0.381)
			)
			(layers "F.Cu" "F.Mask" "F.Paste")
			(net "GND")
		)
		(pad "B76" smd rect
			(at 21.999956 -1.131062 90)
			(size 0.508 2.4892)
			(drill
				(offset 0 0.381)
			)
			(layers "F.Cu" "F.Mask" "F.Paste")
			(net "GND")
		)
		(pad "B77" smd rect
			(at 22.800056 -1.131062 90)
			(size 0.508 2.4892)
			(drill
				(offset 0 0.381)
			)
			(layers "F.Cu" "F.Mask" "F.Paste")
			(net "PE_RX3_DR11_N")
		)
		(pad "B78" smd rect
			(at 23.599902 -1.131062 90)
			(size 0.508 2.4892)
			(drill
				(offset 0 0.381)
			)
			(layers "F.Cu" "F.Mask" "F.Paste")
			(net "PE_RX3_DR11_P")
		)
		(pad "B79" smd rect
			(at 24.400002 -1.131062 90)
			(size 0.508 2.4892)
			(drill
				(offset 0 0.381)
			)
			(layers "F.Cu" "F.Mask" "F.Paste")
			(net "GND")
		)
		(pad "B80" smd rect
			(at 25.200102 -1.131062 90)
			(size 0.508 2.4892)
			(drill
				(offset 0 0.381)
			)
			(layers "F.Cu" "F.Mask" "F.Paste")
			(net "GND")
		)
		(pad "B81" smd rect
			(at 25.999948 -1.131062 90)
			(size 0.508 2.4892)
			(drill
				(offset 0 0.381)
			)
			(layers "F.Cu" "F.Mask" "F.Paste")
			(net "PE_RX4_DR11_N")
		)
		(pad "B82" smd rect
			(at 26.800048 -1.131062 90)
			(size 0.508 2.4892)
			(drill
				(offset 0 0.381)
			)
			(layers "F.Cu" "F.Mask" "F.Paste")
			(net "PE_RX4_DR11_P")
		)
		(pad "B83" smd rect
			(at 27.599894 -1.131062 90)
			(size 0.508 2.4892)
			(drill
				(offset 0 0.381)
			)
			(layers "F.Cu" "F.Mask" "F.Paste")
			(net "GND")
		)
		(pad "B84" smd rect
			(at 28.399994 -1.131062 90)
			(size 0.508 2.4892)
			(drill
				(offset 0 0.381)
			)
			(layers "F.Cu" "F.Mask" "F.Paste")
			(net "GND")
		)
		(pad "B85" smd rect
			(at 29.200094 -1.131062 90)
			(size 0.508 2.4892)
			(drill
				(offset 0 0.381)
			)
			(layers "F.Cu" "F.Mask" "F.Paste")
			(net "PE_RX1_DR6_N")
		)
		(pad "B86" smd rect
			(at 29.99994 -1.131062 90)
			(size 0.508 2.4892)
			(drill
				(offset 0 0.381)
			)
			(layers "F.Cu" "F.Mask" "F.Paste")
			(net "PE_RX1_DR6_P")
		)
		(pad "B87" smd rect
			(at 30.80004 -1.131062 90)
			(size 0.508 2.4892)
			(drill
				(offset 0 0.381)
			)
			(layers "F.Cu" "F.Mask" "F.Paste")
			(net "GND")
		)
		(pad "B88" smd rect
			(at 31.599886 -1.131062 90)
			(size 0.508 2.4892)
			(drill
				(offset 0 0.381)
			)
			(layers "F.Cu" "F.Mask" "F.Paste")
			(net "GND")
		)
		(pad "B89" smd rect
			(at 32.399986 -1.131062 90)
			(size 0.508 2.4892)
			(drill
				(offset 0 0.381)
			)
			(layers "F.Cu" "F.Mask" "F.Paste")
			(net "PE_RX2_DR6_N")
		)
		(pad "B90" smd rect
			(at 33.200086 -1.131062 90)
			(size 0.508 2.4892)
			(drill
				(offset 0 0.381)
			)
			(layers "F.Cu" "F.Mask" "F.Paste")
			(net "PE_RX2_DR6_P")
		)
		(pad "B91" smd rect
			(at 33.999932 -1.131062 90)
			(size 0.508 2.4892)
			(drill
				(offset 0 0.381)
			)
			(layers "F.Cu" "F.Mask" "F.Paste")
			(net "GND")
		)
		(pad "B92" smd rect
			(at 34.800032 -1.131062 90)
			(size 0.508 2.4892)
			(drill
				(offset 0 0.381)
			)
			(layers "F.Cu" "F.Mask" "F.Paste")
			(net "GND")
		)
		(pad "B93" smd rect
			(at 35.599878 -1.131062 90)
			(size 0.508 2.4892)
			(drill
				(offset 0 0.381)
			)
			(layers "F.Cu" "F.Mask" "F.Paste")
			(net "PE_RX3_DR6_N")
		)
		(pad "B94" smd rect
			(at 36.399978 -1.131062 90)
			(size 0.508 2.4892)
			(drill
				(offset 0 0.381)
			)
			(layers "F.Cu" "F.Mask" "F.Paste")
			(net "PE_RX3_DR6_P")
		)
		(pad "B95" smd rect
			(at 37.200078 -1.131062 90)
			(size 0.508 2.4892)
			(drill
				(offset 0 0.381)
			)
			(layers "F.Cu" "F.Mask" "F.Paste")
			(net "GND")
		)
		(pad "B96" smd rect
			(at 37.999924 -1.131062 90)
			(size 0.508 2.4892)
			(drill
				(offset 0 0.381)
			)
			(layers "F.Cu" "F.Mask" "F.Paste")
			(net "GND")
		)
		(pad "B97" smd rect
			(at 38.800024 -1.131062 90)
			(size 0.508 2.4892)
			(drill
				(offset 0 0.381)
			)
			(layers "F.Cu" "F.Mask" "F.Paste")
			(net "PE_RX4_DR6_N")
		)
		(pad "B98" smd rect
			(at 39.600124 -1.131062 90)
			(size 0.508 2.4892)
			(drill
				(offset 0 0.381)
			)
			(layers "F.Cu" "F.Mask" "F.Paste")
			(net "PE_RX4_DR6_P")
		)
		(pad "B99" smd rect
			(at 40.39997 -1.131062 90)
			(size 0.508 2.4892)
			(drill
				(offset 0 0.381)
			)
			(layers "F.Cu" "F.Mask" "F.Paste")
			(net "GND")
		)
		(pad "B100" smd rect
			(at 41.20007 -1.131062 90)
			(size 0.508 2.4892)
			(drill
				(offset 0 0.381)
			)
			(layers "F.Cu" "F.Mask" "F.Paste")
			(net "SSD6_PERST_N")
		)
	)
)
